FILE_TYPE = MULTI_PHYS_TABLE;

PART '74HCT2G125DP_TSSOP8'
CLASS=IC

{========================================================================================}
:CLS_PN              = JEDEC_TYPE            | ALT_SYMBOLS             | DESCRIPTION                                                                 | CPN_STATUS ;
{========================================================================================}
 'G220-10098-01'     = 'SOP8_118_P0256_V3'   | '(SOP8_118_P0256_V3)'   | 'IC,BUFFER,1.65V-5.5V,8P,TSSOP8'                                            | ''        
 'G229-10116-01'     = 'SOP8_091_P0197_H035' | '(SOP8_091_P0197_H035)' | 'IC,DUAL BUFFER/DRIVER WITH 3-STATE OUTPUTS,0.8V TO 3.6V,-40 TO 85,CSSOP-8' | ''        
 'G220-00055-01'     = 'SOP8_091_P0197_H035' | '(SOP8_091_P0197_H035)' | 'IC,NC7WV125,BUFFER,3_STATE,SMT-8'                                          | ''        

END_PART

END.

